FILE_TYPE = CONNECTIVITY;
{Allegro Design Entry HDL 17.2-2016 S081 (4005846) 1/11/2022}
"PAGE_NUMBER" = 209;
0"NC";
END.
